(kicad_pcb
	(version 20260206)
	(generator "pcbnew")
	(generator_version "10.0")
	(general
		(thickness 1.6)
		(legacy_teardrops no)
	)
	(paper "A4")
	(title_block
		(title "Bryce Canyon_R.DPB_16317-1_OCP.brd")
		(comment 1 "Bryce Canyon / footprints 393-398 of 2099")
	)
	(layers
		(0 "F.Cu" signal "TOP")
		(4 "In1.Cu" signal "L2GND")
		(6 "In2.Cu" signal "L3")
		(8 "In3.Cu" signal "L4VCC")
		(10 "In4.Cu" signal "L5VCC")
		(12 "In5.Cu" signal "L6")
		(14 "In6.Cu" signal "L7GND")
		(2 "B.Cu" signal "BOTTOM")
		(9 "F.Adhes" user "F.Adhesive")
		(11 "B.Adhes" user "B.Adhesive")
		(13 "F.Paste" user "Package Geometry/Pastemask Top")
		(15 "B.Paste" user "Package Geometry/Pastemask Bottom")
		(5 "F.SilkS" user "Ref Des/Silkscreen Top")
		(7 "B.SilkS" user "Ref Des/Silkscreen Bottom")
		(1 "F.Mask" user "Board Geometry/Soldermask Top")
		(3 "B.Mask" user "Board Geometry/Soldermask Bottom")
		(17 "Dwgs.User" user "User.Drawings")
		(19 "Cmts.User" user "User.Comments")
		(21 "Eco1.User" user "User.Eco1")
		(23 "Eco2.User" user "User.Eco2")
		(25 "Edge.Cuts" user "Board Geometry/Outline")
		(27 "Margin" user)
		(31 "F.CrtYd" user "Package Geometry/Place Bound Top")
		(29 "B.CrtYd" user "Package Geometry/Place Bound Bottom")
		(35 "F.Fab" user "Ref Des/Assembly Top")
		(33 "B.Fab" user "Ref Des/Assembly Bottom")
	)
	(footprint ""
		(layer "F.Cu")
		(at 311.900062 -377.219972 180)
		(property "Reference" "FLED3"
			(at 0 0 180)
			(layer "F.SilkS")
			(hide yes)
			(effects
				(font
					(size 1.27 1.27)
				)
			)
		)
		(property "Value" "LED-BY-14-GP"
			(at -4.7752 -2.1844 180)
			(unlocked yes)
			(layer "F.Fab")
			(hide yes)
			(effects
				(font
					(size 1.016 1.016)
					(thickness 0.1524)
				)
			)
		)
		(property "Device Type" "LED-100-3PH206"
			(at -4.7752 -3.7084 180)
			(unlocked yes)
			(layer "F.Fab")
			(hide yes)
			(effects
				(font
					(size 1.016 1.016)
					(thickness 0.1524)
				)
			)
		)
		(duplicate_pad_numbers_are_jumpers no)
		(fp_line
			(start 3.7592 8.0264)
			(end -3.7592 8.0264)
			(stroke
				(width 0.1524)
				(type default)
			)
			(layer "F.SilkS")
		)
		(fp_line
			(start 3.7592 -1.524)
			(end 3.7592 8.0264)
			(stroke
				(width 0.1524)
				(type default)
			)
			(layer "F.SilkS")
		)
		(fp_line
			(start 1.87833 3.63474)
			(end 0.58293 2.33934)
			(stroke
				(width 0.1524)
				(type default)
			)
			(layer "F.SilkS")
		)
		(fp_line
			(start 1.87833 2.33934)
			(end 2.81813 2.33934)
			(stroke
				(width 0.1524)
				(type default)
			)
			(layer "F.SilkS")
		)
		(fp_line
			(start 1.87833 1.04394)
			(end 1.87833 3.63474)
			(stroke
				(width 0.1524)
				(type default)
			)
			(layer "F.SilkS")
		)
		(fp_line
			(start 0.58293 3.05054)
			(end 0.58293 1.42494)
			(stroke
				(width 0.1524)
				(type default)
			)
			(layer "F.SilkS")
		)
		(fp_line
			(start 0.58293 2.33934)
			(end 1.87833 1.04394)
			(stroke
				(width 0.1524)
				(type default)
			)
			(layer "F.SilkS")
		)
		(fp_line
			(start -0.45847 3.05054)
			(end -0.45847 1.42494)
			(stroke
				(width 0.1524)
				(type default)
			)
			(layer "F.SilkS")
		)
		(fp_line
			(start -0.45847 2.33934)
			(end 0.58293 2.33934)
			(stroke
				(width 0.1524)
				(type default)
			)
			(layer "F.SilkS")
		)
		(fp_line
			(start -0.45847 2.33934)
			(end -1.75387 1.04394)
			(stroke
				(width 0.1524)
				(type default)
			)
			(layer "F.SilkS")
		)
		(fp_line
			(start -1.75387 3.63474)
			(end -0.45847 2.33934)
			(stroke
				(width 0.1524)
				(type default)
			)
			(layer "F.SilkS")
		)
		(fp_line
			(start -1.75387 2.33934)
			(end -3.45567 2.33934)
			(stroke
				(width 0.1524)
				(type default)
			)
			(layer "F.SilkS")
		)
		(fp_line
			(start -1.75387 1.04394)
			(end -1.75387 3.63474)
			(stroke
				(width 0.1524)
				(type default)
			)
			(layer "F.SilkS")
		)
		(fp_line
			(start -3.7592 8.0264)
			(end -3.7592 -1.524)
			(stroke
				(width 0.1524)
				(type default)
			)
			(layer "F.SilkS")
		)
		(fp_line
			(start -3.7592 -1.524)
			(end 3.7592 -1.524)
			(stroke
				(width 0.1524)
				(type default)
			)
			(layer "F.SilkS")
		)
		(fp_circle
			(center 2.54 0)
			(end 1.5494 0)
			(stroke
				(width 0.3048)
				(type default)
			)
			(fill no)
			(layer "F.SilkS")
		)
		(fp_circle
			(center 0 0)
			(end -0.9906 0)
			(stroke
				(width 0.3048)
				(type default)
			)
			(fill no)
			(layer "F.SilkS")
		)
		(fp_circle
			(center -2.54 0)
			(end -3.5306 0)
			(stroke
				(width 0.3048)
				(type default)
			)
			(fill no)
			(layer "F.SilkS")
		)
		(fp_rect
			(start -3.5052 7.7724)
			(end 3.5052 -1.27)
			(stroke
				(width 0)
				(type default)
			)
			(fill no)
			(layer "F.CrtYd")
		)
		(fp_poly
			(pts
				(xy -4.0132 8.2804) (xy -4.0132 -1.778) (xy -3.5052 -1.778) (xy -3.5052 7.7724) (xy 3.5052 7.7724)
				(xy 3.5052 -1.27) (xy -3.50012 -1.27) (xy -3.50012 -1.778) (xy 4.0132 -1.778) (xy 4.0132 8.2804)
			)
			(stroke
				(width 0)
				(type default)
			)
			(fill no)
			(layer "F.CrtYd")
		)
		(fp_rect
			(start -4.0132 8.2804)
			(end 4.0132 -1.778)
			(stroke
				(width 0)
				(type default)
			)
			(fill no)
			(layer "F.Fab")
		)
		(pad "1" thru_hole circle
			(at -2.54 0 180)
			(size 1.27 1.27)
			(drill 0.889)
			(layers "*.Cu" "*.Mask")
			(remove_unused_layers no)
			(net "FAN_LED_BLUE2")
			(clearance 0.1651)
			(thermal_gap 0.1651)
		)
		(pad "2" thru_hole circle
			(at 0 0 180)
			(size 1.27 1.27)
			(drill 0.889)
			(layers "*.Cu" "*.Mask")
			(remove_unused_layers no)
			(net "GND")
			(clearance 0.1651)
			(thermal_gap 0.1651)
		)
		(pad "3" thru_hole circle
			(at 2.54 0 180)
			(size 1.27 1.27)
			(drill 0.889)
			(layers "*.Cu" "*.Mask")
			(remove_unused_layers no)
			(net "FAN_LED_YELLOW_2")
			(clearance 0.1651)
			(thermal_gap 0.1651)
		)
	)
	(footprint ""
		(layer "F.Cu")
		(at 66.7258 -262.128 90)
		(property "Reference" "C43"
			(at 0 0 90)
			(layer "F.SilkS")
			(hide yes)
			(effects
				(font
					(size 1.27 1.27)
				)
			)
		)
		(property "Value" "SCD01U50V2KX-1GP"
			(at 1.1811 -2.7051 90)
			(unlocked yes)
			(layer "F.Fab")
			(hide yes)
			(effects
				(font
					(size 1.016 1.016)
					(thickness 0.1524)
				)
			)
		)
		(property "Device Type" "C402H22"
			(at 1.1811 -4.2291 90)
			(unlocked yes)
			(layer "F.Fab")
			(hide yes)
			(effects
				(font
					(size 1.016 1.016)
					(thickness 0.1524)
				)
			)
		)
		(duplicate_pad_numbers_are_jumpers no)
		(fp_rect
			(start -0.4318 0.9525)
			(end 0.4318 -0.9525)
			(stroke
				(width 0)
				(type default)
			)
			(fill no)
			(layer "F.CrtYd")
		)
		(fp_rect
			(start -0.4318 0.9525)
			(end 0.4318 -0.9525)
			(stroke
				(width 0)
				(type default)
			)
			(fill no)
			(layer "F.Fab")
		)
		(pad "1" smd custom
			(at 0 -0.4445 90)
			(size 0.1524 0.1524)
			(layers "F.Cu" "F.Mask" "F.Paste")
			(net "HDD_PRSNT_1")
			(options
				(clearance outline)
				(anchor circle)
			)
			(primitives
				(gr_poly
					(pts
						(arc
							(start 0.3048 -0.2032)
							(mid 0.275042 -0.275042)
							(end 0.2032 -0.3048)
						)
						(arc
							(start -0.2032 -0.3048)
							(mid -0.275042 -0.275042)
							(end -0.3048 -0.2032)
						)
						(arc
							(start -0.3048 0.2032)
							(mid -0.275042 0.275042)
							(end -0.2032 0.3048)
						)
						(arc
							(start 0.2032 0.3048)
							(mid 0.275042 0.275042)
							(end 0.3048 0.2032)
						)
					)
					(width 0)
					(fill yes)
				)
			)
		)
		(pad "2" smd custom
			(at 0 0.4445 90)
			(size 0.1524 0.1524)
			(layers "F.Cu" "F.Mask" "F.Paste")
			(net "GND")
			(options
				(clearance outline)
				(anchor circle)
			)
			(primitives
				(gr_poly
					(pts
						(arc
							(start 0.3048 -0.2032)
							(mid 0.275042 -0.275042)
							(end 0.2032 -0.3048)
						)
						(arc
							(start -0.2032 -0.3048)
							(mid -0.275042 -0.275042)
							(end -0.3048 -0.2032)
						)
						(arc
							(start -0.3048 0.2032)
							(mid -0.275042 0.275042)
							(end -0.2032 0.3048)
						)
						(arc
							(start 0.2032 0.3048)
							(mid 0.275042 0.275042)
							(end 0.3048 0.2032)
						)
					)
					(width 0)
					(fill yes)
				)
			)
		)
	)
	(footprint ""
		(layer "F.Cu")
		(at 143.002 -23.114 90)
		(property "Reference" "R721"
			(at 0 0 90)
			(layer "F.SilkS")
			(hide yes)
			(effects
				(font
					(size 1.27 1.27)
				)
			)
		)
		(property "Value" "4K7R2J-2-GP"
			(at 0.064008 -3.993896 90)
			(unlocked yes)
			(layer "F.Fab")
			(hide yes)
			(effects
				(font
					(size 1.016 1.016)
					(thickness 0.1524)
				)
			)
		)
		(property "Device Type" "R402H16"
			(at 0.064008 -5.517896 90)
			(unlocked yes)
			(layer "F.Fab")
			(hide yes)
			(effects
				(font
					(size 1.016 1.016)
					(thickness 0.1524)
				)
			)
		)
		(duplicate_pad_numbers_are_jumpers no)
		(fp_line
			(start 0.508 -0.9398)
			(end -0.508 -0.9398)
			(stroke
				(width 0.1524)
				(type default)
			)
			(layer "F.SilkS")
		)
		(fp_line
			(start -0.508 -0.9398)
			(end -0.508 0.9398)
			(stroke
				(width 0.1524)
				(type default)
			)
			(layer "F.SilkS")
		)
		(fp_rect
			(start -0.508 0.9398)
			(end 0.508 -0.9398)
			(stroke
				(width 0)
				(type default)
			)
			(fill no)
			(layer "F.CrtYd")
		)
		(fp_rect
			(start -0.508 0.9398)
			(end 0.508 -0.9398)
			(stroke
				(width 0)
				(type default)
			)
			(fill no)
			(layer "F.Fab")
		)
		(pad "1" smd custom
			(at 0 -0.4445 90)
			(size 0.1397 0.1397)
			(layers "F.Cu" "F.Mask" "F.Paste")
			(net "P12V_B")
			(options
				(clearance outline)
				(anchor circle)
			)
			(primitives
				(gr_poly
					(pts
						(arc
							(start -0.1778 -0.2794)
							(mid -0.249642 -0.249642)
							(end -0.2794 -0.1778)
						)
						(arc
							(start -0.2794 0.1778)
							(mid -0.249642 0.249642)
							(end -0.1778 0.2794)
						)
						(arc
							(start 0.1778 0.2794)
							(mid 0.249642 0.249642)
							(end 0.2794 0.1778)
						)
						(arc
							(start 0.2794 -0.1778)
							(mid 0.249642 -0.249642)
							(end 0.1778 -0.2794)
						)
					)
					(width 0)
					(fill yes)
				)
			)
		)
		(pad "2" smd custom
			(at 0 0.4445 90)
			(size 0.1397 0.1397)
			(layers "F.Cu" "F.Mask" "F.Paste")
			(net "SW_HDD_P28")
			(options
				(clearance outline)
				(anchor circle)
			)
			(primitives
				(gr_poly
					(pts
						(arc
							(start -0.1778 -0.2794)
							(mid -0.249642 -0.249642)
							(end -0.2794 -0.1778)
						)
						(arc
							(start -0.2794 0.1778)
							(mid -0.249642 0.249642)
							(end -0.1778 0.2794)
						)
						(arc
							(start 0.1778 0.2794)
							(mid 0.249642 0.249642)
							(end 0.2794 0.1778)
						)
						(arc
							(start 0.2794 -0.1778)
							(mid 0.249642 -0.249642)
							(end 0.1778 -0.2794)
						)
					)
					(width 0)
					(fill yes)
				)
			)
		)
	)
	(footprint ""
		(layer "F.Cu")
		(at 221.996 -220.853 -90)
		(property "Reference" "R17"
			(at 0 0 270)
			(layer "F.SilkS")
			(hide yes)
			(effects
				(font
					(size 1.27 1.27)
				)
			)
		)
		(property "Value" "4K7R2F-GP"
			(at 0.064008 -3.993896 270)
			(unlocked yes)
			(layer "F.Fab")
			(hide yes)
			(effects
				(font
					(size 1.016 1.016)
					(thickness 0.1524)
				)
			)
		)
		(property "Device Type" "R402H16"
			(at 0.064008 -5.517896 270)
			(unlocked yes)
			(layer "F.Fab")
			(hide yes)
			(effects
				(font
					(size 1.016 1.016)
					(thickness 0.1524)
				)
			)
		)
		(duplicate_pad_numbers_are_jumpers no)
		(fp_line
			(start -0.508 -0.9398)
			(end -0.508 0.9398)
			(stroke
				(width 0.1524)
				(type default)
			)
			(layer "F.SilkS")
		)
		(fp_line
			(start 0.508 -0.9398)
			(end -0.508 -0.9398)
			(stroke
				(width 0.1524)
				(type default)
			)
			(layer "F.SilkS")
		)
		(fp_rect
			(start -0.508 0.9398)
			(end 0.508 -0.9398)
			(stroke
				(width 0)
				(type default)
			)
			(fill no)
			(layer "F.CrtYd")
		)
		(fp_rect
			(start -0.508 0.9398)
			(end 0.508 -0.9398)
			(stroke
				(width 0)
				(type default)
			)
			(fill no)
			(layer "F.Fab")
		)
		(pad "1" smd custom
			(at 0 -0.4445 270)
			(size 0.1397 0.1397)
			(layers "F.Cu" "F.Mask" "F.Paste")
			(net "P3V3_STBY_B")
			(options
				(clearance outline)
				(anchor circle)
			)
			(primitives
				(gr_poly
					(pts
						(arc
							(start -0.1778 -0.2794)
							(mid -0.249642 -0.249642)
							(end -0.2794 -0.1778)
						)
						(arc
							(start -0.2794 0.1778)
							(mid -0.249642 0.249642)
							(end -0.1778 0.2794)
						)
						(arc
							(start 0.1778 0.2794)
							(mid 0.249642 0.249642)
							(end 0.2794 0.1778)
						)
						(arc
							(start 0.2794 -0.1778)
							(mid 0.249642 -0.249642)
							(end 0.1778 -0.2794)
						)
					)
					(width 0)
					(fill yes)
				)
			)
		)
		(pad "2" smd custom
			(at 0 0.4445 270)
			(size 0.1397 0.1397)
			(layers "F.Cu" "F.Mask" "F.Paste")
			(net "IO_EXP1_HDD_FAULT_A0")
			(options
				(clearance outline)
				(anchor circle)
			)
			(primitives
				(gr_poly
					(pts
						(arc
							(start -0.1778 -0.2794)
							(mid -0.249642 -0.249642)
							(end -0.2794 -0.1778)
						)
						(arc
							(start -0.2794 0.1778)
							(mid -0.249642 0.249642)
							(end -0.1778 0.2794)
						)
						(arc
							(start 0.1778 0.2794)
							(mid 0.249642 0.249642)
							(end 0.2794 0.1778)
						)
						(arc
							(start 0.2794 -0.1778)
							(mid 0.249642 -0.249642)
							(end 0.1778 -0.2794)
						)
					)
					(width 0)
					(fill yes)
				)
			)
		)
	)
	(footprint ""
		(layer "F.Cu")
		(at 415.0868 -146.6342 180)
		(property "Reference" "R553"
			(at 0 0 180)
			(layer "F.SilkS")
			(hide yes)
			(effects
				(font
					(size 1.27 1.27)
				)
			)
		)
		(property "Value" "10KR2F-2-GP"
			(at 0.064008 -3.993896 180)
			(unlocked yes)
			(layer "F.Fab")
			(hide yes)
			(effects
				(font
					(size 1.016 1.016)
					(thickness 0.1524)
				)
			)
		)
		(property "Device Type" "R402H16"
			(at 0.064008 -5.517896 180)
			(unlocked yes)
			(layer "F.Fab")
			(hide yes)
			(effects
				(font
					(size 1.016 1.016)
					(thickness 0.1524)
				)
			)
		)
		(duplicate_pad_numbers_are_jumpers no)
		(fp_line
			(start 0.508 -0.9398)
			(end -0.508 -0.9398)
			(stroke
				(width 0.1524)
				(type default)
			)
			(layer "F.SilkS")
		)
		(fp_line
			(start -0.508 -0.9398)
			(end -0.508 0.9398)
			(stroke
				(width 0.1524)
				(type default)
			)
			(layer "F.SilkS")
		)
		(fp_rect
			(start -0.508 0.9398)
			(end 0.508 -0.9398)
			(stroke
				(width 0)
				(type default)
			)
			(fill no)
			(layer "F.CrtYd")
		)
		(fp_rect
			(start -0.508 0.9398)
			(end 0.508 -0.9398)
			(stroke
				(width 0)
				(type default)
			)
			(fill no)
			(layer "F.Fab")
		)
		(pad "1" smd custom
			(at 0 -0.4445 180)
			(size 0.1397 0.1397)
			(layers "F.Cu" "F.Mask" "F.Paste")
			(net "P3V3_STBY_B")
			(options
				(clearance outline)
				(anchor circle)
			)
			(primitives
				(gr_poly
					(pts
						(arc
							(start -0.1778 -0.2794)
							(mid -0.249642 -0.249642)
							(end -0.2794 -0.1778)
						)
						(arc
							(start -0.2794 0.1778)
							(mid -0.249642 0.249642)
							(end -0.1778 0.2794)
						)
						(arc
							(start 0.1778 0.2794)
							(mid 0.249642 0.249642)
							(end 0.2794 0.1778)
						)
						(arc
							(start 0.2794 -0.1778)
							(mid 0.249642 -0.249642)
							(end 0.1778 -0.2794)
						)
					)
					(width 0)
					(fill yes)
				)
			)
		)
		(pad "2" smd custom
			(at 0 0.4445 180)
			(size 0.1397 0.1397)
			(layers "F.Cu" "F.Mask" "F.Paste")
			(net "HDD_PRSNT_21")
			(options
				(clearance outline)
				(anchor circle)
			)
			(primitives
				(gr_poly
					(pts
						(arc
							(start -0.1778 -0.2794)
							(mid -0.249642 -0.249642)
							(end -0.2794 -0.1778)
						)
						(arc
							(start -0.2794 0.1778)
							(mid -0.249642 0.249642)
							(end -0.1778 0.2794)
						)
						(arc
							(start 0.1778 0.2794)
							(mid 0.249642 0.249642)
							(end 0.2794 0.1778)
						)
						(arc
							(start 0.2794 -0.1778)
							(mid 0.249642 -0.249642)
							(end 0.1778 -0.2794)
						)
					)
					(width 0)
					(fill yes)
				)
			)
		)
	)
	(footprint ""
		(layer "F.Cu")
		(at 44.1706 -5.3086 -90)
		(property "Reference" "R124"
			(at 0 0 270)
			(layer "F.SilkS")
			(hide yes)
			(effects
				(font
					(size 1.27 1.27)
				)
			)
		)
		(property "Value" "4K7R2F-GP"
			(at 0.064008 -3.993896 270)
			(unlocked yes)
			(layer "F.Fab")
			(hide yes)
			(effects
				(font
					(size 1.016 1.016)
					(thickness 0.1524)
				)
			)
		)
		(property "Device Type" "R402H16"
			(at 0.064008 -5.517896 270)
			(unlocked yes)
			(layer "F.Fab")
			(hide yes)
			(effects
				(font
					(size 1.016 1.016)
					(thickness 0.1524)
				)
			)
		)
		(duplicate_pad_numbers_are_jumpers no)
		(fp_line
			(start -0.508 -0.9398)
			(end -0.508 0.9398)
			(stroke
				(width 0.1524)
				(type default)
			)
			(layer "F.SilkS")
		)
		(fp_line
			(start 0.508 -0.9398)
			(end -0.508 -0.9398)
			(stroke
				(width 0.1524)
				(type default)
			)
			(layer "F.SilkS")
		)
		(fp_rect
			(start -0.508 0.9398)
			(end 0.508 -0.9398)
			(stroke
				(width 0)
				(type default)
			)
			(fill no)
			(layer "F.CrtYd")
		)
		(fp_rect
			(start -0.508 0.9398)
			(end 0.508 -0.9398)
			(stroke
				(width 0)
				(type default)
			)
			(fill no)
			(layer "F.Fab")
		)
		(pad "1" smd custom
			(at 0 -0.4445 270)
			(size 0.1397 0.1397)
			(layers "F.Cu" "F.Mask" "F.Paste")
			(net "P3V3_STBY_A")
			(options
				(clearance outline)
				(anchor circle)
			)
			(primitives
				(gr_poly
					(pts
						(arc
							(start -0.1778 -0.2794)
							(mid -0.249642 -0.249642)
							(end -0.2794 -0.1778)
						)
						(arc
							(start -0.2794 0.1778)
							(mid -0.249642 0.249642)
							(end -0.1778 0.2794)
						)
						(arc
							(start 0.1778 0.2794)
							(mid 0.249642 0.249642)
							(end 0.2794 0.1778)
						)
						(arc
							(start 0.2794 -0.1778)
							(mid 0.249642 -0.249642)
							(end 0.1778 -0.2794)
						)
					)
					(width 0)
					(fill yes)
				)
			)
		)
		(pad "2" smd custom
			(at 0 0.4445 270)
			(size 0.1397 0.1397)
			(layers "F.Cu" "F.Mask" "F.Paste")
			(net "TEMP1_A2")
			(options
				(clearance outline)
				(anchor circle)
			)
			(primitives
				(gr_poly
					(pts
						(arc
							(start -0.1778 -0.2794)
							(mid -0.249642 -0.249642)
							(end -0.2794 -0.1778)
						)
						(arc
							(start -0.2794 0.1778)
							(mid -0.249642 0.249642)
							(end -0.1778 0.2794)
						)
						(arc
							(start 0.1778 0.2794)
							(mid 0.249642 0.249642)
							(end 0.2794 0.1778)
						)
						(arc
							(start 0.2794 -0.1778)
							(mid 0.249642 -0.249642)
							(end 0.1778 -0.2794)
						)
					)
					(width 0)
					(fill yes)
				)
			)
		)
	)
)
